# T6G (Grand Teton) — schematic netlist excerpt (pin names and nets, part order shuffled) for the footprints in the layout excerpt that follows; sources: Cadence DE-HDL packaged netlist, KiCad conversion of 04192023_DAF0TMB3IC0_F0TG_MB_C_brd_V02_OCP.brd

C1282  Q_CAP  0.1UF 25V 10% X7R  pkg 0402  page 145 : A = P3V3_E1S_0 ; B = GND
R4077  Q_RES  1 1% CHIP  pkg 0402LF  page 233 : A = VFG3P3_CLK_GEN ; B = VFG_3P3A_CLK_GEN

(kicad_pcb
	(version 20260206)
	(generator "pcbnew")
	(generator_version "10.0")
	(general
		(thickness 1.6)
		(legacy_teardrops no)
	)
	(paper "A4")
	(title_block
		(title "04192023_DAF0TMB3IC0_F0TG_MB_C_brd_V02_OCP.brd")
		(comment 1 "Grand Teton / footprints 7602-7603 of 8354")
	)
	(layers
		(0 "F.Cu" signal "TOP")
		(4 "In1.Cu" signal "GND")
		(6 "In2.Cu" signal "IN1")
		(8 "In3.Cu" signal "GND1")
		(10 "In4.Cu" signal "IN2")
		(12 "In5.Cu" signal "GND2")
		(14 "In6.Cu" signal "IN3")
		(16 "In7.Cu" signal "GND3")
		(18 "In8.Cu" signal "VCC")
		(20 "In9.Cu" signal "VCC1")
		(22 "In10.Cu" signal "GND4")
		(24 "In11.Cu" signal "IN4")
		(26 "In12.Cu" signal "GND5")
		(28 "In13.Cu" signal "IN5")
		(30 "In14.Cu" signal "GND6")
		(32 "In15.Cu" signal "IN6")
		(34 "In16.Cu" signal "GND7")
		(2 "B.Cu" signal "BOTTOM")
		(9 "F.Adhes" user "F.Adhesive")
		(11 "B.Adhes" user "B.Adhesive")
		(13 "F.Paste" user "Package Geometry/Pastemask Top")
		(15 "B.Paste" user "Package Geometry/Pastemask Bottom")
		(5 "F.SilkS" user "Ref Des/Silkscreen Top")
		(7 "B.SilkS" user "Ref Des/Silkscreen Bottom")
		(1 "F.Mask" user "Board Geometry/Soldermask Top")
		(3 "B.Mask" user "Board Geometry/Soldermask Bottom")
		(17 "Dwgs.User" user "User.Drawings")
		(19 "Cmts.User" user "User.Comments")
		(21 "Eco1.User" user "User.Eco1")
		(23 "Eco2.User" user "User.Eco2")
		(25 "Edge.Cuts" user "Board Geometry/Outline")
		(27 "Margin" user)
		(31 "F.CrtYd" user "Package Geometry/Place Bound Top")
		(29 "B.CrtYd" user "Package Geometry/Place Bound Bottom")
		(35 "F.Fab" user "Ref Des/Assembly Top")
		(33 "B.Fab" user "Ref Des/Assembly Bottom")
	)
	(footprint ""
		(layer "B.Cu")
		(at 236.67593 -49.120044)
		(property "Reference" "C1282"
			(at 0 0 0)
			(layer "B.SilkS")
			(hide yes)
			(effects
				(font
					(size 1.27 1.27)
				)
				(justify mirror)
			)
		)
		(property "Value" ""
			(at 0 0 0)
			(layer "B.Fab")
			(effects
				(font
					(size 1.27 1.27)
				)
				(justify mirror)
			)
		)
		(duplicate_pad_numbers_are_jumpers no)
		(fp_line
			(start -0.7874 -0.4064)
			(end -0.7874 0.4064)
			(stroke
				(width 0.1524)
				(type default)
			)
			(layer "B.SilkS")
		)
		(fp_line
			(start -0.7874 0.4064)
			(end 0.7874 0.4064)
			(stroke
				(width 0.1524)
				(type default)
			)
			(layer "B.SilkS")
		)
		(fp_line
			(start 0.7874 -0.4064)
			(end -0.7874 -0.4064)
			(stroke
				(width 0.1524)
				(type default)
			)
			(layer "B.SilkS")
		)
		(fp_line
			(start 0.7874 0.4064)
			(end 0.7874 -0.4064)
			(stroke
				(width 0.1524)
				(type default)
			)
			(layer "B.SilkS")
		)
		(fp_line
			(start -0.67945 -0.3048)
			(end -0.67945 0.3048)
			(stroke
				(width 0.1)
				(type default)
			)
			(layer "B.Fab")
		)
		(fp_line
			(start -0.67945 0.3048)
			(end -0.120396 0.3048)
			(stroke
				(width 0.1)
				(type default)
			)
			(layer "B.Fab")
		)
		(fp_line
			(start -0.12065 -0.3048)
			(end -0.67945 -0.3048)
			(stroke
				(width 0.1)
				(type default)
			)
			(layer "B.Fab")
		)
		(fp_line
			(start -0.12065 -0.2794)
			(end -0.12065 -0.3048)
			(stroke
				(width 0.1)
				(type default)
			)
			(layer "B.Fab")
		)
		(fp_line
			(start -0.120396 0.2794)
			(end 0.12065 0.2794)
			(stroke
				(width 0.1)
				(type default)
			)
			(layer "B.Fab")
		)
		(fp_line
			(start -0.120396 0.3048)
			(end -0.120396 0.2794)
			(stroke
				(width 0.1)
				(type default)
			)
			(layer "B.Fab")
		)
		(fp_line
			(start 0.12065 -0.305054)
			(end 0.12065 -0.2794)
			(stroke
				(width 0.1)
				(type default)
			)
			(layer "B.Fab")
		)
		(fp_line
			(start 0.12065 -0.2794)
			(end -0.12065 -0.2794)
			(stroke
				(width 0.1)
				(type default)
			)
			(layer "B.Fab")
		)
		(fp_line
			(start 0.12065 0.2794)
			(end 0.12065 0.3048)
			(stroke
				(width 0.1)
				(type default)
			)
			(layer "B.Fab")
		)
		(fp_line
			(start 0.12065 0.3048)
			(end 0.67945 0.3048)
			(stroke
				(width 0.1)
				(type default)
			)
			(layer "B.Fab")
		)
		(fp_line
			(start 0.67945 -0.305054)
			(end 0.12065 -0.305054)
			(stroke
				(width 0.1)
				(type default)
			)
			(layer "B.Fab")
		)
		(fp_line
			(start 0.67945 0.3048)
			(end 0.67945 -0.305054)
			(stroke
				(width 0.1)
				(type default)
			)
			(layer "B.Fab")
		)
		(pad "1" smd circle
			(at 0.40005 0 180)
			(size 0 0)
			(layers "B.Cu" "B.Mask" "B.Paste")
			(net "P3V3_E1S_0")
		)
		(pad "2" smd circle
			(at -0.40005 0 180)
			(size 0 0)
			(layers "B.Cu" "B.Mask" "B.Paste")
			(net "GND")
		)
	)
	(footprint ""
		(layer "B.Cu")
		(at 15.436088 -135.48741 90)
		(property "Reference" "R4077"
			(at 0 0 90)
			(layer "B.SilkS")
			(hide yes)
			(effects
				(font
					(size 1.27 1.27)
				)
				(justify mirror)
			)
		)
		(property "Value" ""
			(at 0 0 90)
			(layer "B.Fab")
			(effects
				(font
					(size 1.27 1.27)
				)
				(justify mirror)
			)
		)
		(duplicate_pad_numbers_are_jumpers no)
		(fp_line
			(start 0.7874 -0.4064)
			(end -0.7874 -0.4064)
			(stroke
				(width 0.1524)
				(type default)
			)
			(layer "B.SilkS")
		)
		(fp_line
			(start -0.7874 -0.4064)
			(end -0.7874 0.4064)
			(stroke
				(width 0.1524)
				(type default)
			)
			(layer "B.SilkS")
		)
		(fp_line
			(start 0.7874 0.4064)
			(end 0.7874 -0.4064)
			(stroke
				(width 0.1524)
				(type default)
			)
			(layer "B.SilkS")
		)
		(fp_line
			(start -0.7874 0.4064)
			(end 0.7874 0.4064)
			(stroke
				(width 0.1524)
				(type default)
			)
			(layer "B.SilkS")
		)
		(fp_line
			(start 0.67945 -0.305054)
			(end 0.12065 -0.305054)
			(stroke
				(width 0.1)
				(type default)
			)
			(layer "B.Fab")
		)
		(fp_line
			(start 0.12065 -0.305054)
			(end 0.12065 -0.2794)
			(stroke
				(width 0.1)
				(type default)
			)
			(layer "B.Fab")
		)
		(fp_line
			(start -0.12065 -0.3048)
			(end -0.67945 -0.3048)
			(stroke
				(width 0.1)
				(type default)
			)
			(layer "B.Fab")
		)
		(fp_line
			(start -0.67945 -0.3048)
			(end -0.67945 0.3048)
			(stroke
				(width 0.1)
				(type default)
			)
			(layer "B.Fab")
		)
		(fp_line
			(start 0.12065 -0.2794)
			(end -0.12065 -0.2794)
			(stroke
				(width 0.1)
				(type default)
			)
			(layer "B.Fab")
		)
		(fp_line
			(start -0.12065 -0.2794)
			(end -0.12065 -0.3048)
			(stroke
				(width 0.1)
				(type default)
			)
			(layer "B.Fab")
		)
		(fp_line
			(start 0.12065 0.2794)
			(end 0.12065 0.3048)
			(stroke
				(width 0.1)
				(type default)
			)
			(layer "B.Fab")
		)
		(fp_line
			(start -0.120396 0.2794)
			(end 0.12065 0.2794)
			(stroke
				(width 0.1)
				(type default)
			)
			(layer "B.Fab")
		)
		(fp_line
			(start 0.67945 0.3048)
			(end 0.67945 -0.305054)
			(stroke
				(width 0.1)
				(type default)
			)
			(layer "B.Fab")
		)
		(fp_line
			(start 0.12065 0.3048)
			(end 0.67945 0.3048)
			(stroke
				(width 0.1)
				(type default)
			)
			(layer "B.Fab")
		)
		(fp_line
			(start -0.120396 0.3048)
			(end -0.120396 0.2794)
			(stroke
				(width 0.1)
				(type default)
			)
			(layer "B.Fab")
		)
		(fp_line
			(start -0.67945 0.3048)
			(end -0.120396 0.3048)
			(stroke
				(width 0.1)
				(type default)
			)
			(layer "B.Fab")
		)
		(pad "1" smd circle
			(at 0.40005 0 270)
			(size 0 0)
			(layers "B.Cu" "B.Mask" "B.Paste")
			(net "VFG3P3_CLK_GEN")
		)
		(pad "2" smd circle
			(at -0.40005 0 270)
			(size 0 0)
			(layers "B.Cu" "B.Mask" "B.Paste")
			(net "VFG_3P3A_CLK_GEN")
		)
	)
)
